# T6G (Grand Teton) — schematic netlist excerpt (pin names and nets, part order shuffled) for the footprints in the layout excerpt that follows; sources: Cadence DE-HDL packaged netlist, KiCad conversion of 04192023_DAF0TMB3IC0_F0TG_MB_C_brd_V02_OCP.brd

J20  SCONN288_DDR506112002KQ  IO  pkg DDR288S_1-1VXC  page 96
  VIN_BULK0  = P12V_MEM_CPU0
  RFU0  = NC
  VIN_MGMT  = P3V3_AUX
  HSCL  = I3C_SPD_DDRK_CPU0_SCL
  HSDA  = I3C_SPD_DDRK_CPU0_SDA
  VSS0  = GND
  DQ0_A  = M_K_CPU0_SA_DQ<0>
  VSS1  = GND
  DQ1_A  = M_K_CPU0_SA_DQ<1>
  VSS2  = GND
  DQS0_A_T  = M_K_CPU0_SA_DQS_DP<0>
  DQS0_A_C  = M_K_CPU0_SA_DQS_DN<0>
  VSS3  = GND
  DQ4_A  = M_K_CPU0_SA_DQ<4>
  VSS4  = GND
  DQ5_A  = M_K_CPU0_SA_DQ<5>
  VSS5  = GND
  DQ8_A  = M_K_CPU0_SA_DQ<8>
  VSS6  = GND
  DQ9_A  = M_K_CPU0_SA_DQ<9>
  VSS7  = GND
  DQS1_A_T  = M_K_CPU0_SA_DQS_DP<1>
  DQS1_A_C  = M_K_CPU0_SA_DQS_DN<1>
  VSS8  = GND
  DQ12_A  = M_K_CPU0_SA_DQ<12>
  VSS9  = GND
  DQ13_A  = M_K_CPU0_SA_DQ<13>
  VSS10  = GND
  DQ16_A  = M_K_CPU0_SA_DQ<16>
  VSS11  = GND
  DQ17_A  = M_K_CPU0_SA_DQ<17>
  VSS12  = GND
  DQS2_A_T  = M_K_CPU0_SA_DQS_DP<2>
  DQS2_A_C  = M_K_CPU0_SA_DQS_DN<2>
  VSS13  = GND
  DQ20_A  = M_K_CPU0_SA_DQ<20>
  VSS14  = GND
  DQ21_A  = M_K_CPU0_SA_DQ<21>
  VSS15  = GND
  DQ24_A  = M_K_CPU0_SA_DQ<24>
  VSS16  = GND
  DQ25_A  = M_K_CPU0_SA_DQ<25>
  VSS17  = GND
  DQS3_A_T  = M_K_CPU0_SA_DQS_DP<3>
  DQS3_A_C  = M_K_CPU0_SA_DQS_DN<3>
  VSS18  = GND
  DQ28_A  = M_K_CPU0_SA_DQ<28>
  VSS19  = GND
  DQ29_A  = M_K_CPU0_SA_DQ<29>
  VSS20  = GND
  CB0_A  = M_K_CPU0_SA_CB<0>
  VSS21  = GND
  CB1_A  = M_K_CPU0_SA_CB<1>
  VSS22  = GND
  DQS4_A_T  = M_K_CPU0_SA_DQS_DP<4>
  DQS4_A_C  = M_K_CPU0_SA_DQS_DN<4>
  VSS23  = GND
  CB4_A  = M_K_CPU0_SA_CB<4>
  VSS24  = GND
  CB5_A  = M_K_CPU0_SA_CB<5>
  VSS25  = GND
  ALERT_N  = M_K_CPU0_ALERT_N
  VSS26  = GND
  CS0_A_N  = M_K_CPU0_SA_CS_N<0>
  VSS27  = GND
  CA0_A  = M_K_CPU0_SA_CA<0>
  VSS28  = GND
  CA2_A  = M_K_CPU0_SA_CA<2>
  VSS29  = GND
  CA4_A  = M_K_CPU0_SA_CA<4>
  VSS30  = GND
  CA6_A  = M_K_CPU0_SA_CA<6>
  VSS31  = GND
  PAR_A  = M_K_CPU0_SA_PAR
  VSS32  = GND
  CA0_B  = M_K_CPU0_SB_CA<0>
  VSS33  = GND
  CA2_B  = M_K_CPU0_SB_CA<2>
  VSS34  = GND
  CA4_B  = M_K_CPU0_SB_CA<4>
  VSS35  = GND
  CA6_B  = M_K_CPU0_SB_CA<6>
  VSS36  = GND
  CS0_B_N  = M_K_CPU0_SB_CS_N<0>
  VSS37  = GND
  \lbd||rsp_a_n\  = M_K_CPU0_SA_RSP<0>
  \lbs||rsp_b_n\  = M_K_CPU0_SB_RSP<0>
  VSS38  = GND
  CB4_B  = M_K_CPU0_SB_CB<4>
  VSS39  = GND
  CB5_B  = M_K_CPU0_SB_CB<5>
  VSS40  = GND
  \dqs9_b_t||tdqs9_b_t||dbi4_b_n\  = M_K_CPU0_SB_DQS_DP<9>
  \dqs9_b_c||tdqs9_b_c\  = M_K_CPU0_SB_DQS_DN<9>
  VSS41  = GND
  CB0_B  = M_K_CPU0_SB_CB<0>
  VSS42  = GND
  CB1_B  = M_K_CPU0_SB_CB<1>
  VSS43  = GND
  DQ0_B  = M_K_CPU0_SB_DQ<0>
  VSS44  = GND
  DQ1_B  = M_K_CPU0_SB_DQ<1>
  VSS45  = GND
  DQS0_B_T  = M_K_CPU0_SB_DQS_DP<0>
  DQS0_B_C  = M_K_CPU0_SB_DQS_DN<0>
  VSS46  = GND
  DQ4_B  = M_K_CPU0_SB_DQ<4>
  VSS47  = GND
  DQ5_B  = M_K_CPU0_SB_DQ<5>
  VSS48  = GND
  DQ8_B  = M_K_CPU0_SB_DQ<8>
  VSS49  = GND
  DQ9_B  = M_K_CPU0_SB_DQ<9>
  VSS50  = GND
  DQS1_B_T  = M_K_CPU0_SB_DQS_DP<1>
  DQS1_B_C  = M_K_CPU0_SB_DQS_DN<1>
  VSS51  = GND
  DQ12_B  = M_K_CPU0_SB_DQ<12>
  VSS52  = GND
  DQ13_B  = M_K_CPU0_SB_DQ<13>
  VSS53  = GND
  DQ16_B  = M_K_CPU0_SB_DQ<16>
  VSS54  = GND
  DQ17_B  = M_K_CPU0_SB_DQ<17>
  VSS55  = GND
  DQS2_B_T  = M_K_CPU0_SB_DQS_DP<2>
  DQS2_B_C  = M_K_CPU0_SB_DQS_DN<2>
  VSS56  = GND
  DQ20_B  = M_K_CPU0_SB_DQ<20>
  VSS57  = GND
  DQ21_B  = M_K_CPU0_SB_DQ<21>
  VSS58  = GND
  DQ24_B  = M_K_CPU0_SB_DQ<24>
  VSS59  = GND
  DQ25_B  = M_K_CPU0_SB_DQ<25>
  VSS60  = GND
  DQS3_B_T  = M_K_CPU0_SB_DQS_DP<3>
  DQS3_B_C  = M_K_CPU0_SB_DQS_DN<3>
  VSS61  = GND
  DQ28_B  = M_K_CPU0_SB_DQ<28>
  VSS62  = GND
  DQ29_B  = M_K_CPU0_SB_DQ<29>
  VSS63  = GND
  RFU1  = NC
  VIN_BULK1  = P12V_MEM_CPU0
  VIN_BULK2  = P12V_MEM_CPU0
  \pwr_good||fail_n\  = PWRGD_CHK_CPU0_DIMM
  HAS  = PD_CHK_CPU0_DIMM_SAA
  RFU2  = NC
  RFU3  = NC
  VSS64  = GND
  DQ2_A  = M_K_CPU0_SA_DQ<2>
  VSS65  = GND
  DQ3_A  = M_K_CPU0_SA_DQ<3>
  VSS66  = GND
  \dqs5_a_c||tdqs5_a_c||dqs5_a_t||tdqs5_a_t\  = M_K_CPU0_SA_DQS_DN<5>
  \dqs5_a_t||tdqs5_a_t\  = M_K_CPU0_SA_DQS_DP<5>
  VSS67  = GND
  DQ6_A  = M_K_CPU0_SA_DQ<6>
  VSS68  = GND
  DQ7_A  = M_K_CPU0_SA_DQ<7>
  VSS69  = GND
  DQ10_A  = M_K_CPU0_SA_DQ<10>
  VSS70  = GND
  DQ11_A  = M_K_CPU0_SA_DQ<11>
  VSS71  = GND
  \dqs6_a_c||tdqs6_a_c||dqs6_a_t||tdqs6_a_t\  = M_K_CPU0_SA_DQS_DN<6>
  \dqs6_a_t||tdqs6_a_t\  = M_K_CPU0_SA_DQS_DP<6>
  VSS72  = GND
  DQ14_A  = M_K_CPU0_SA_DQ<14>
  VSS73  = GND
  DQ15_A  = M_K_CPU0_SA_DQ<15>
  VSS74  = GND
  DQ18_A  = M_K_CPU0_SA_DQ<18>
  VSS75  = GND
  DQ19_A  = M_K_CPU0_SA_DQ<19>
  VSS76  = GND
  \dqs7_a_c||tdqs7_a_c\  = M_K_CPU0_SA_DQS_DN<7>
  \dqs7_a_t||tdqs7_a_t\  = M_K_CPU0_SA_DQS_DP<7>
  VSS77  = GND
  DQ22_A  = M_K_CPU0_SA_DQ<22>
  VSS78  = GND
  DQ23_A  = M_K_CPU0_SA_DQ<23>
  VSS79  = GND
  DQ26_A  = M_K_CPU0_SA_DQ<26>
  VSS80  = GND
  DQ27_A  = M_K_CPU0_SA_DQ<27>
  VSS81  = GND
  \dqs8_a_c||tdqs8_a_c\  = M_K_CPU0_SA_DQS_DN<8>
  \dqs8_a_t||tdqs8_a_t\  = M_K_CPU0_SA_DQS_DP<8>
  VSS82  = GND
  DQ30_A  = M_K_CPU0_SA_DQ<30>
  VSS83  = GND
  DQ31_A  = M_K_CPU0_SA_DQ<31>
  VSS84  = GND
  CB2_A  = M_K_CPU0_SA_CB<2>
  VSS85  = GND
  CB3_A  = M_K_CPU0_SA_CB<3>
  VSS86  = GND
  \dqs9_a_c||tdqs9_a_c\  = M_K_CPU0_SA_DQS_DN<9>
  \dqs9_a_t||tdqs9_a_t\  = M_K_CPU0_SA_DQS_DP<9>
  VSS87  = GND
  CB6_A  = M_K_CPU0_SA_CB<6>
  VSS88  = GND
  CB7_A  = M_K_CPU0_SA_CB<7>
  VSS89  = GND
  RESET_N  = M_K_CPU0_RESET_N
  VSS90  = GND
  CS1_A_N  = M_K_CPU0_SA_CS_N<1>
  VSS91  = GND
  CA1_A  = M_K_CPU0_SA_CA<1>
  VSS92  = GND
  CA3_A  = M_K_CPU0_SA_CA<3>
  VSS93  = GND
  CA5_A  = M_K_CPU0_SA_CA<5>
  VSS94  = GND
  CK_T  = M_K_CPU0_CLK_DP<0>
  CK_C  = M_K_CPU0_CLK_DN<0>
  VSS95  = GND
  RFU4  = NC
  CA1_B  = M_K_CPU0_SB_CA<1>
  VSS96  = GND
  CA3_B  = M_K_CPU0_SB_CA<3>
  VSS97  = GND
  CA5_B  = M_K_CPU0_SB_CA<5>
  VSS98  = GND
  PAR_B  = M_K_CPU0_SB_PAR
  VSS99  = GND
  CS1_B_N  = M_K_CPU0_SB_CS_N<1>
  VSS100  = GND
  RFU5  = NC
  RFU6  = NC
  VSS101  = GND
  CB6_B  = M_K_CPU0_SB_CB<6>
  VSS102  = GND
  CB7_B  = M_K_CPU0_SB_CB<7>
  VSS103  = GND
  DQS4_B_C  = M_K_CPU0_SB_DQS_DN<4>
  DQS4_B_T  = M_K_CPU0_SB_DQS_DP<4>
  VSS104  = GND
  CB2_B  = M_K_CPU0_SB_CB<2>
  VSS105  = GND
  CB3_B  = M_K_CPU0_SB_CB<3>
  VSS106  = GND
  DQ2_B  = M_K_CPU0_SB_DQ<2>
  VSS107  = GND
  DQ3_B  = M_K_CPU0_SB_DQ<3>
  VSS108  = GND
  \dqs5_b_c||tdqs5_b_c\  = M_K_CPU0_SB_DQS_DN<5>
  \dqs5_b_t||tdqs5_b_t\  = M_K_CPU0_SB_DQS_DP<5>
  VSS109  = GND
  DQ6_B  = M_K_CPU0_SB_DQ<6>
  VSS110  = GND
  DQ7_B  = M_K_CPU0_SB_DQ<7>
  VSS111  = GND
  DQ10_B  = M_K_CPU0_SB_DQ<10>
  VSS112  = GND
  DQ11_B  = M_K_CPU0_SB_DQ<11>
  VSS113  = GND
  \dqs6_b_c||tdqs6_b_c\  = M_K_CPU0_SB_DQS_DN<6>
  \dqs6_b_t||tdqs6_b_t\  = M_K_CPU0_SB_DQS_DP<6>
  VSS114  = GND
  DQ14_B  = M_K_CPU0_SB_DQ<14>
  VSS115  = GND
  DQ15_B  = M_K_CPU0_SB_DQ<15>
  VSS116  = GND
  DQ18_B  = M_K_CPU0_SB_DQ<18>
  VSS117  = GND
  DQ19_B  = M_K_CPU0_SB_DQ<19>
  VSS118  = GND
  \dqs7_b_c||tdqs7_b_c\  = M_K_CPU0_SB_DQS_DN<7>
  \dqs7_b_t||tdqs7_b_t\  = M_K_CPU0_SB_DQS_DP<7>
  VSS119  = GND
  DQ22_B  = M_K_CPU0_SB_DQ<22>
  VSS120  = GND
  DQ23_B  = M_K_CPU0_SB_DQ<23>
  VSS121  = GND
  DQ26_B  = M_K_CPU0_SB_DQ<26>
  VSS122  = GND
  DQ27_B  = M_K_CPU0_SB_DQ<27>
  VSS123  = GND
  \dqs8_b_c||tdqs8_b_c\  = M_K_CPU0_SB_DQS_DN<8>
  \dqs8_b_t||tdqs8_b_t\  = M_K_CPU0_SB_DQS_DP<8>
  VSS124  = GND
  DQ30_B  = M_K_CPU0_SB_DQ<30>
  VSS125  = GND
  DQ31_B  = M_K_CPU0_SB_DQ<31>
  VSS126  = GND
  G1  = GND
  G2  = GND
  G3  = GND

(kicad_pcb
	(version 20260206)
	(generator "pcbnew")
	(generator_version "10.0")
	(general
		(thickness 1.6)
		(legacy_teardrops no)
	)
	(paper "A4")
	(title_block
		(title "04192023_DAF0TMB3IC0_F0TG_MB_C_brd_V02_OCP.brd")
		(comment 1 "Grand Teton / footprint 2165 of 8354 (J20), pads 231-276 of 291")
	)
	(layers
		(0 "F.Cu" signal "TOP")
		(4 "In1.Cu" signal "GND")
		(6 "In2.Cu" signal "IN1")
		(8 "In3.Cu" signal "GND1")
		(10 "In4.Cu" signal "IN2")
		(12 "In5.Cu" signal "GND2")
		(14 "In6.Cu" signal "IN3")
		(16 "In7.Cu" signal "GND3")
		(18 "In8.Cu" signal "VCC")
		(20 "In9.Cu" signal "VCC1")
		(22 "In10.Cu" signal "GND4")
		(24 "In11.Cu" signal "IN4")
		(26 "In12.Cu" signal "GND5")
		(28 "In13.Cu" signal "IN5")
		(30 "In14.Cu" signal "GND6")
		(32 "In15.Cu" signal "IN6")
		(34 "In16.Cu" signal "GND7")
		(2 "B.Cu" signal "BOTTOM")
		(9 "F.Adhes" user "F.Adhesive")
		(11 "B.Adhes" user "B.Adhesive")
		(13 "F.Paste" user "Package Geometry/Pastemask Top")
		(15 "B.Paste" user "Package Geometry/Pastemask Bottom")
		(5 "F.SilkS" user "Ref Des/Silkscreen Top")
		(7 "B.SilkS" user "Ref Des/Silkscreen Bottom")
		(1 "F.Mask" user "Board Geometry/Soldermask Top")
		(3 "B.Mask" user "Board Geometry/Soldermask Bottom")
		(17 "Dwgs.User" user "User.Drawings")
		(19 "Cmts.User" user "User.Comments")
		(21 "Eco1.User" user "User.Eco1")
		(23 "Eco2.User" user "User.Eco2")
		(25 "Edge.Cuts" user "Board Geometry/Outline")
		(27 "Margin" user)
		(31 "F.CrtYd" user "Package Geometry/Place Bound Top")
		(29 "B.CrtYd" user "Package Geometry/Place Bound Bottom")
		(35 "F.Fab" user "Ref Des/Assembly Top")
		(33 "B.Fab" user "Ref Des/Assembly Bottom")
	)
	(footprint ""
		(layer "F.Cu")
		(at 444.594234 -255.560068 180)
		(property "Reference" "J20"
			(at 1.631188 -81.796128 0)
			(unlocked yes)
			(layer "F.SilkS")
			(effects
				(font
					(size 0.7874 0.5842)
					(thickness 0.1524)
				)
			)
		)
		(property "Value" ""
			(at 0 0 180)
			(layer "F.Fab")
			(effects
				(font
					(size 1.27 1.27)
				)
			)
		)
		(duplicate_pad_numbers_are_jumpers no)
		(pad "231" smd rect
			(at 2.050034 14.875002 90)
			(size 0.519938 1.4986)
			(layers "F.Cu" "F.Mask" "F.Paste")
			(net "Net_2394")
		)
		(pad "232" smd rect
			(at 2.050034 15.724886 90)
			(size 0.519938 1.4986)
			(layers "F.Cu" "F.Mask" "F.Paste")
			(net "Net_2395")
		)
		(pad "233" smd rect
			(at 2.050034 16.575024 90)
			(size 0.519938 1.4986)
			(layers "F.Cu" "F.Mask" "F.Paste")
			(net "GND")
		)
		(pad "234" smd rect
			(at 2.050034 17.424908 90)
			(size 0.519938 1.4986)
			(layers "F.Cu" "F.Mask" "F.Paste")
			(net "M_K_CPU0_SB_CB<6>")
		)
		(pad "235" smd rect
			(at 2.050034 18.275046 90)
			(size 0.519938 1.4986)
			(layers "F.Cu" "F.Mask" "F.Paste")
			(net "GND")
		)
		(pad "236" smd rect
			(at 2.050034 19.12493 90)
			(size 0.519938 1.4986)
			(layers "F.Cu" "F.Mask" "F.Paste")
			(net "M_K_CPU0_SB_CB<7>")
		)
		(pad "237" smd rect
			(at 2.050034 19.975068 90)
			(size 0.519938 1.4986)
			(layers "F.Cu" "F.Mask" "F.Paste")
			(net "GND")
		)
		(pad "238" smd rect
			(at 2.050034 20.824952 90)
			(size 0.519938 1.4986)
			(layers "F.Cu" "F.Mask" "F.Paste")
			(net "M_K_CPU0_SB_DQS_DN<4>")
		)
		(pad "239" smd rect
			(at 2.050034 21.67509 90)
			(size 0.519938 1.4986)
			(layers "F.Cu" "F.Mask" "F.Paste")
			(net "M_K_CPU0_SB_DQS_DP<4>")
		)
		(pad "240" smd rect
			(at 2.050034 22.524974 90)
			(size 0.519938 1.4986)
			(layers "F.Cu" "F.Mask" "F.Paste")
			(net "GND")
		)
		(pad "241" smd rect
			(at 2.050034 23.375112 90)
			(size 0.519938 1.4986)
			(layers "F.Cu" "F.Mask" "F.Paste")
			(net "M_K_CPU0_SB_CB<2>")
		)
		(pad "242" smd rect
			(at 2.050034 24.224996 90)
			(size 0.519938 1.4986)
			(layers "F.Cu" "F.Mask" "F.Paste")
			(net "GND")
		)
		(pad "243" smd rect
			(at 2.050034 25.07488 90)
			(size 0.519938 1.4986)
			(layers "F.Cu" "F.Mask" "F.Paste")
			(net "M_K_CPU0_SB_CB<3>")
		)
		(pad "244" smd rect
			(at 2.050034 25.925018 90)
			(size 0.519938 1.4986)
			(layers "F.Cu" "F.Mask" "F.Paste")
			(net "GND")
		)
		(pad "245" smd rect
			(at 2.050034 26.774902 90)
			(size 0.519938 1.4986)
			(layers "F.Cu" "F.Mask" "F.Paste")
			(net "M_K_CPU0_SB_DQ<2>")
		)
		(pad "246" smd rect
			(at 2.050034 27.62504 90)
			(size 0.519938 1.4986)
			(layers "F.Cu" "F.Mask" "F.Paste")
			(net "GND")
		)
		(pad "247" smd rect
			(at 2.050034 28.474924 90)
			(size 0.519938 1.4986)
			(layers "F.Cu" "F.Mask" "F.Paste")
			(net "M_K_CPU0_SB_DQ<3>")
		)
		(pad "248" smd rect
			(at 2.050034 29.325062 90)
			(size 0.519938 1.4986)
			(layers "F.Cu" "F.Mask" "F.Paste")
			(net "GND")
		)
		(pad "249" smd rect
			(at 2.050034 30.174946 90)
			(size 0.519938 1.4986)
			(layers "F.Cu" "F.Mask" "F.Paste")
			(net "M_K_CPU0_SB_DQS_DN<5>")
		)
		(pad "250" smd rect
			(at 2.050034 31.025084 90)
			(size 0.519938 1.4986)
			(layers "F.Cu" "F.Mask" "F.Paste")
			(net "M_K_CPU0_SB_DQS_DP<5>")
		)
		(pad "251" smd rect
			(at 2.050034 31.874968 90)
			(size 0.519938 1.4986)
			(layers "F.Cu" "F.Mask" "F.Paste")
			(net "GND")
		)
		(pad "252" smd rect
			(at 2.050034 32.725106 90)
			(size 0.519938 1.4986)
			(layers "F.Cu" "F.Mask" "F.Paste")
			(net "M_K_CPU0_SB_DQ<6>")
		)
		(pad "253" smd rect
			(at 2.050034 33.57499 90)
			(size 0.519938 1.4986)
			(layers "F.Cu" "F.Mask" "F.Paste")
			(net "GND")
		)
		(pad "254" smd rect
			(at 2.050034 34.425128 90)
			(size 0.519938 1.4986)
			(layers "F.Cu" "F.Mask" "F.Paste")
			(net "M_K_CPU0_SB_DQ<7>")
		)
		(pad "255" smd rect
			(at 2.050034 35.275012 90)
			(size 0.519938 1.4986)
			(layers "F.Cu" "F.Mask" "F.Paste")
			(net "GND")
		)
		(pad "256" smd rect
			(at 2.050034 36.124896 90)
			(size 0.519938 1.4986)
			(layers "F.Cu" "F.Mask" "F.Paste")
			(net "M_K_CPU0_SB_DQ<10>")
		)
		(pad "257" smd rect
			(at 2.050034 36.975034 90)
			(size 0.519938 1.4986)
			(layers "F.Cu" "F.Mask" "F.Paste")
			(net "GND")
		)
		(pad "258" smd rect
			(at 2.050034 37.824918 90)
			(size 0.519938 1.4986)
			(layers "F.Cu" "F.Mask" "F.Paste")
			(net "M_K_CPU0_SB_DQ<11>")
		)
		(pad "259" smd rect
			(at 2.050034 38.675056 90)
			(size 0.519938 1.4986)
			(layers "F.Cu" "F.Mask" "F.Paste")
			(net "GND")
		)
		(pad "260" smd rect
			(at 2.050034 39.52494 90)
			(size 0.519938 1.4986)
			(layers "F.Cu" "F.Mask" "F.Paste")
			(net "M_K_CPU0_SB_DQS_DN<6>")
		)
		(pad "261" smd rect
			(at 2.050034 40.375078 90)
			(size 0.519938 1.4986)
			(layers "F.Cu" "F.Mask" "F.Paste")
			(net "M_K_CPU0_SB_DQS_DP<6>")
		)
		(pad "262" smd rect
			(at 2.050034 41.224962 90)
			(size 0.519938 1.4986)
			(layers "F.Cu" "F.Mask" "F.Paste")
			(net "GND")
		)
		(pad "263" smd rect
			(at 2.050034 42.0751 90)
			(size 0.519938 1.4986)
			(layers "F.Cu" "F.Mask" "F.Paste")
			(net "M_K_CPU0_SB_DQ<14>")
		)
		(pad "264" smd rect
			(at 2.050034 42.924984 90)
			(size 0.519938 1.4986)
			(layers "F.Cu" "F.Mask" "F.Paste")
			(net "GND")
		)
		(pad "265" smd rect
			(at 2.050034 43.775122 90)
			(size 0.519938 1.4986)
			(layers "F.Cu" "F.Mask" "F.Paste")
			(net "M_K_CPU0_SB_DQ<15>")
		)
		(pad "266" smd rect
			(at 2.050034 44.625006 90)
			(size 0.519938 1.4986)
			(layers "F.Cu" "F.Mask" "F.Paste")
			(net "GND")
		)
		(pad "267" smd rect
			(at 2.050034 45.47489 90)
			(size 0.519938 1.4986)
			(layers "F.Cu" "F.Mask" "F.Paste")
			(net "M_K_CPU0_SB_DQ<18>")
		)
		(pad "268" smd rect
			(at 2.050034 46.325028 90)
			(size 0.519938 1.4986)
			(layers "F.Cu" "F.Mask" "F.Paste")
			(net "GND")
		)
		(pad "269" smd rect
			(at 2.050034 47.174912 90)
			(size 0.519938 1.4986)
			(layers "F.Cu" "F.Mask" "F.Paste")
			(net "M_K_CPU0_SB_DQ<19>")
		)
		(pad "270" smd rect
			(at 2.050034 48.02505 90)
			(size 0.519938 1.4986)
			(layers "F.Cu" "F.Mask" "F.Paste")
			(net "GND")
		)
		(pad "271" smd rect
			(at 2.050034 48.874934 90)
			(size 0.519938 1.4986)
			(layers "F.Cu" "F.Mask" "F.Paste")
			(net "M_K_CPU0_SB_DQS_DN<7>")
		)
		(pad "272" smd rect
			(at 2.050034 49.725072 90)
			(size 0.519938 1.4986)
			(layers "F.Cu" "F.Mask" "F.Paste")
			(net "M_K_CPU0_SB_DQS_DP<7>")
		)
		(pad "273" smd rect
			(at 2.050034 50.574956 90)
			(size 0.519938 1.4986)
			(layers "F.Cu" "F.Mask" "F.Paste")
			(net "GND")
		)
		(pad "274" smd rect
			(at 2.050034 51.425094 90)
			(size 0.519938 1.4986)
			(layers "F.Cu" "F.Mask" "F.Paste")
			(net "M_K_CPU0_SB_DQ<22>")
		)
		(pad "275" smd rect
			(at 2.050034 52.274978 90)
			(size 0.519938 1.4986)
			(layers "F.Cu" "F.Mask" "F.Paste")
			(net "GND")
		)
		(pad "276" smd rect
			(at 2.050034 53.125116 90)
			(size 0.519938 1.4986)
			(layers "F.Cu" "F.Mask" "F.Paste")
			(net "M_K_CPU0_SB_DQ<23>")
		)
	)
)
